(kicad_pcb
	(version 20260206)
	(generator "pcbnew")
	(generator_version "10.0")
	(general
		(thickness 1.6)
		(legacy_teardrops no)
	)
	(paper "A4")
	(title_block
		(title "fcb — Lightning_FCB_BRD.brd")
		(comment 1 "Lightning (Wiwynn / Facebook NVMe JBOF) / footprints 12-16 of 495")
	)
	(layers
		(0 "F.Cu" signal "TOP")
		(4 "In1.Cu" signal "L2GND")
		(6 "In2.Cu" signal "L3VCC")
		(2 "B.Cu" signal "BOTTOM")
		(9 "F.Adhes" user "F.Adhesive")
		(11 "B.Adhes" user "B.Adhesive")
		(13 "F.Paste" user "Package Geometry/Pastemask Top")
		(15 "B.Paste" user "Package Geometry/Pastemask Bottom")
		(5 "F.SilkS" user "Ref Des/Silkscreen Top")
		(7 "B.SilkS" user "Ref Des/Silkscreen Bottom")
		(1 "F.Mask" user "Board Geometry/Soldermask Top")
		(3 "B.Mask" user "Board Geometry/Soldermask Bottom")
		(17 "Dwgs.User" user "User.Drawings")
		(19 "Cmts.User" user "User.Comments")
		(21 "Eco1.User" user "User.Eco1")
		(23 "Eco2.User" user "User.Eco2")
		(25 "Edge.Cuts" user "Board Geometry/Outline")
		(27 "Margin" user)
		(31 "F.CrtYd" user "Package Geometry/Place Bound Top")
		(29 "B.CrtYd" user "Package Geometry/Place Bound Bottom")
		(35 "F.Fab" user "Ref Des/Assembly Top")
		(33 "B.Fab" user "Ref Des/Assembly Bottom")
	)
	(footprint ""
		(layer "F.Cu")
		(at 36.957 -174.244)
		(property "Reference" "PQ9"
			(at 0 0 0)
			(layer "F.SilkS")
			(hide yes)
			(effects
				(font
					(size 1.27 1.27)
				)
			)
		)
		(property "Value" "PMBS3904-1-GP"
			(at 0 -9.0932 0)
			(unlocked yes)
			(layer "F.Fab")
			(hide yes)
			(effects
				(font
					(size 1.016 1.016)
					(thickness 0.1524)
				)
			)
		)
		(property "Device Type" "SOT-23-10H44"
			(at 0 -10.6172 0)
			(unlocked yes)
			(layer "F.Fab")
			(hide yes)
			(effects
				(font
					(size 1.016 1.016)
					(thickness 0.1524)
				)
			)
		)
		(duplicate_pad_numbers_are_jumpers no)
		(fp_line
			(start -1.7526 1.8796)
			(end -1.7526 0.9906)
			(stroke
				(width 0.3302)
				(type default)
			)
			(layer "F.SilkS")
		)
		(fp_line
			(start -1.651 -1.778)
			(end -1.651 1.778)
			(stroke
				(width 0.1524)
				(type default)
			)
			(layer "F.SilkS")
		)
		(fp_line
			(start -1.651 1.778)
			(end 1.651 1.778)
			(stroke
				(width 0.1524)
				(type default)
			)
			(layer "F.SilkS")
		)
		(fp_line
			(start -1.279398 2.152142)
			(end -0.9906 1.86309)
			(stroke
				(width 0.0127)
				(type default)
			)
			(layer "F.SilkS")
		)
		(fp_line
			(start -1.279144 2.15265)
			(end -0.701294 2.15265)
			(stroke
				(width 0.0127)
				(type default)
			)
			(layer "F.SilkS")
		)
		(fp_line
			(start -1.260856 2.1336)
			(end -0.720344 2.1336)
			(stroke
				(width 0.0127)
				(type default)
			)
			(layer "F.SilkS")
		)
		(fp_line
			(start -1.251458 2.124202)
			(end -0.729996 2.124202)
			(stroke
				(width 0.0127)
				(type default)
			)
			(layer "F.SilkS")
		)
		(fp_line
			(start -1.241806 2.11455)
			(end -0.739394 2.11455)
			(stroke
				(width 0.0127)
				(type default)
			)
			(layer "F.SilkS")
		)
		(fp_line
			(start -1.232408 2.105152)
			(end -0.749046 2.105152)
			(stroke
				(width 0.0127)
				(type default)
			)
			(layer "F.SilkS")
		)
		(fp_line
			(start -1.222756 2.0955)
			(end -0.758444 2.0955)
			(stroke
				(width 0.0127)
				(type default)
			)
			(layer "F.SilkS")
		)
		(fp_line
			(start -1.213358 2.086102)
			(end -0.768096 2.086102)
			(stroke
				(width 0.0127)
				(type default)
			)
			(layer "F.SilkS")
		)
		(fp_line
			(start -1.203706 2.07645)
			(end -0.777494 2.07645)
			(stroke
				(width 0.0127)
				(type default)
			)
			(layer "F.SilkS")
		)
		(fp_line
			(start -1.194308 2.067052)
			(end -0.787146 2.067052)
			(stroke
				(width 0.0127)
				(type default)
			)
			(layer "F.SilkS")
		)
		(fp_line
			(start -1.184656 2.0574)
			(end -0.796544 2.0574)
			(stroke
				(width 0.0127)
				(type default)
			)
			(layer "F.SilkS")
		)
		(fp_line
			(start -1.175258 2.048002)
			(end -0.806196 2.048002)
			(stroke
				(width 0.0127)
				(type default)
			)
			(layer "F.SilkS")
		)
		(fp_line
			(start -1.165606 2.03835)
			(end -0.815594 2.03835)
			(stroke
				(width 0.0127)
				(type default)
			)
			(layer "F.SilkS")
		)
		(fp_line
			(start -1.156208 2.028952)
			(end -0.825246 2.028952)
			(stroke
				(width 0.0127)
				(type default)
			)
			(layer "F.SilkS")
		)
		(fp_line
			(start -1.146556 2.0193)
			(end -0.834644 2.0193)
			(stroke
				(width 0.0127)
				(type default)
			)
			(layer "F.SilkS")
		)
		(fp_line
			(start -1.137158 2.009902)
			(end -0.844296 2.009902)
			(stroke
				(width 0.0127)
				(type default)
			)
			(layer "F.SilkS")
		)
		(fp_line
			(start -1.127506 2.00025)
			(end -0.853694 2.00025)
			(stroke
				(width 0.0127)
				(type default)
			)
			(layer "F.SilkS")
		)
		(fp_line
			(start -1.118108 1.990852)
			(end -0.863346 1.990852)
			(stroke
				(width 0.0127)
				(type default)
			)
			(layer "F.SilkS")
		)
		(fp_line
			(start -1.108456 1.9812)
			(end -0.872744 1.9812)
			(stroke
				(width 0.0127)
				(type default)
			)
			(layer "F.SilkS")
		)
		(fp_line
			(start -1.099058 1.971802)
			(end -0.882396 1.971802)
			(stroke
				(width 0.0127)
				(type default)
			)
			(layer "F.SilkS")
		)
		(fp_line
			(start -1.089406 1.96215)
			(end -0.891794 1.96215)
			(stroke
				(width 0.0127)
				(type default)
			)
			(layer "F.SilkS")
		)
		(fp_line
			(start -1.080008 1.952752)
			(end -0.901446 1.952752)
			(stroke
				(width 0.0127)
				(type default)
			)
			(layer "F.SilkS")
		)
		(fp_line
			(start -1.070356 1.9431)
			(end -0.910844 1.9431)
			(stroke
				(width 0.0127)
				(type default)
			)
			(layer "F.SilkS")
		)
		(fp_line
			(start -1.060958 1.933702)
			(end -0.920496 1.933702)
			(stroke
				(width 0.0127)
				(type default)
			)
			(layer "F.SilkS")
		)
		(fp_line
			(start -1.051306 1.92405)
			(end -0.929894 1.92405)
			(stroke
				(width 0.0127)
				(type default)
			)
			(layer "F.SilkS")
		)
		(fp_line
			(start -1.041908 1.914652)
			(end -0.939546 1.914652)
			(stroke
				(width 0.0127)
				(type default)
			)
			(layer "F.SilkS")
		)
		(fp_line
			(start -1.032256 1.905)
			(end -0.948944 1.905)
			(stroke
				(width 0.0127)
				(type default)
			)
			(layer "F.SilkS")
		)
		(fp_line
			(start -1.022858 1.895602)
			(end -0.958596 1.895602)
			(stroke
				(width 0.0127)
				(type default)
			)
			(layer "F.SilkS")
		)
		(fp_line
			(start -1.013206 1.88595)
			(end -0.967994 1.88595)
			(stroke
				(width 0.0127)
				(type default)
			)
			(layer "F.SilkS")
		)
		(fp_line
			(start -1.003808 1.876552)
			(end -0.977646 1.876552)
			(stroke
				(width 0.0127)
				(type default)
			)
			(layer "F.SilkS")
		)
		(fp_line
			(start -0.994156 1.8669)
			(end -0.987044 1.8669)
			(stroke
				(width 0.0127)
				(type default)
			)
			(layer "F.SilkS")
		)
		(fp_line
			(start -0.9906 1.86309)
			(end -0.701294 2.15265)
			(stroke
				(width 0.0127)
				(type default)
			)
			(layer "F.SilkS")
		)
		(fp_line
			(start -0.719074 2.145538)
			(end -1.265936 2.14122)
			(stroke
				(width 0.0127)
				(type default)
			)
			(layer "F.SilkS")
		)
		(fp_line
			(start -0.71628 2.15265)
			(end -1.26492 2.15265)
			(stroke
				(width 0.0127)
				(type default)
			)
			(layer "F.SilkS")
		)
		(fp_line
			(start -0.635 1.8796)
			(end -1.7526 1.8796)
			(stroke
				(width 0.3302)
				(type default)
			)
			(layer "F.SilkS")
		)
		(fp_line
			(start 1.651 -1.778)
			(end -1.651 -1.778)
			(stroke
				(width 0.1524)
				(type default)
			)
			(layer "F.SilkS")
		)
		(fp_line
			(start 1.651 1.778)
			(end 1.651 -1.778)
			(stroke
				(width 0.1524)
				(type default)
			)
			(layer "F.SilkS")
		)
		(fp_poly
			(pts
				(xy -1.285748 2.159) (xy -1.285748 1.8796) (xy -1.778 1.8796) (xy -1.778 -1.8796) (xy 1.778 -1.8796)
				(xy 1.778 1.8796) (xy -0.694944 1.8796) (xy -0.694944 2.159)
			)
			(stroke
				(width 0)
				(type default)
			)
			(fill no)
			(layer "F.CrtYd")
		)
		(fp_poly
			(pts
				(xy -1.285748 2.159) (xy -1.285748 1.8796) (xy -1.778 1.8796) (xy -1.778 -1.8796) (xy 1.778 -1.8796)
				(xy 1.778 1.8796) (xy -0.694944 1.8796) (xy -0.694944 2.159)
			)
			(stroke
				(width 0)
				(type default)
			)
			(fill no)
			(layer "F.Fab")
		)
		(pad "1" smd rect
			(at -0.98425 0.9525)
			(size 0.762 1.143)
			(layers "F.Cu" "F.Mask" "F.Paste")
			(net "TEMP_ALM#_IN")
		)
		(pad "2" smd rect
			(at 0.98425 0.9525)
			(size 0.762 1.143)
			(layers "F.Cu" "F.Mask" "F.Paste")
			(net "GND")
		)
		(pad "3" smd rect
			(at 0 -0.9525)
			(size 0.762 1.143)
			(layers "F.Cu" "F.Mask" "F.Paste")
			(net "TEMP_ALM#_IN_D")
		)
	)
	(footprint ""
		(layer "F.Cu")
		(at 7.949946 -443.900052 -90)
		(property "Reference" "LED1"
			(at 0 0 270)
			(layer "F.SilkS")
			(hide yes)
			(effects
				(font
					(size 1.27 1.27)
				)
			)
		)
		(property "Value" "LED-RB-6-GP"
			(at -4.6736 3.8354 270)
			(unlocked yes)
			(layer "F.Fab")
			(hide yes)
			(effects
				(font
					(size 1.016 1.016)
					(thickness 0.1524)
				)
			)
		)
		(property "Device Type" "LED-100-3P-067106H325"
			(at -4.6736 2.3114 270)
			(unlocked yes)
			(layer "F.Fab")
			(hide yes)
			(effects
				(font
					(size 1.016 1.016)
					(thickness 0.1524)
				)
			)
		)
		(duplicate_pad_numbers_are_jumpers no)
		(fp_line
			(start -1.7526 10.414)
			(end -1.7526 6.6548)
			(stroke
				(width 0.1524)
				(type default)
			)
			(layer "F.SilkS")
		)
		(fp_line
			(start 1.7526 10.414)
			(end -1.7526 10.414)
			(stroke
				(width 0.1524)
				(type default)
			)
			(layer "F.SilkS")
		)
		(fp_line
			(start -3.6068 6.6548)
			(end -3.6068 -0.889)
			(stroke
				(width 0.1524)
				(type default)
			)
			(layer "F.SilkS")
		)
		(fp_line
			(start -1.7526 6.6548)
			(end -3.6068 6.6548)
			(stroke
				(width 0.1524)
				(type default)
			)
			(layer "F.SilkS")
		)
		(fp_line
			(start 1.7526 6.6548)
			(end 1.7526 10.414)
			(stroke
				(width 0.1524)
				(type default)
			)
			(layer "F.SilkS")
		)
		(fp_line
			(start 3.6068 6.6548)
			(end 1.7526 6.6548)
			(stroke
				(width 0.1524)
				(type default)
			)
			(layer "F.SilkS")
		)
		(fp_line
			(start -3.6068 -0.889)
			(end 3.6068 -0.889)
			(stroke
				(width 0.1524)
				(type default)
			)
			(layer "F.SilkS")
		)
		(fp_line
			(start 3.6068 -0.889)
			(end 3.6068 6.6548)
			(stroke
				(width 0.1524)
				(type default)
			)
			(layer "F.SilkS")
		)
		(fp_circle
			(center -2.54 0)
			(end -2.54 -0.9906)
			(stroke
				(width 0.3048)
				(type default)
			)
			(fill no)
			(layer "F.SilkS")
		)
		(fp_circle
			(center 0 0)
			(end 0 -0.9906)
			(stroke
				(width 0.3048)
				(type default)
			)
			(fill no)
			(layer "F.SilkS")
		)
		(fp_circle
			(center 2.54 0)
			(end 2.54 -0.9906)
			(stroke
				(width 0.3048)
				(type default)
			)
			(fill no)
			(layer "F.SilkS")
		)
		(fp_poly
			(pts
				(xy -1.4986 10.1473) (xy -1.4986 6.4008) (xy -3.3528 6.4008) (xy -3.3528 -0.3937) (xy 3.3528 -0.3937)
				(xy 3.3528 6.4008) (xy 1.4986 6.4008) (xy 1.4986 10.1473)
			)
			(stroke
				(width 0)
				(type default)
			)
			(fill no)
			(layer "F.CrtYd")
		)
		(fp_poly
			(pts
				(xy -2.0066 10.668) (xy 2.0066 10.668) (xy 2.0066 6.9088) (xy 3.8608 6.9088) (xy 3.8608 2.2098)
				(xy 3.3528 2.2098) (xy 3.3528 6.4008) (xy 1.4986 6.4008) (xy 1.4986 10.1473) (xy -1.4986 10.1473)
				(xy -1.4986 6.4008) (xy -3.3528 6.4008) (xy -3.3528 -0.3937) (xy 3.3528 -0.3937) (xy 3.3528 2.1971)
				(xy 3.8608 2.1971) (xy 3.8608 -1.143) (xy -3.8608 -1.143) (xy -3.8608 6.9088) (xy -2.0066 6.9088)
			)
			(stroke
				(width 0)
				(type default)
			)
			(fill no)
			(layer "F.CrtYd")
		)
		(fp_poly
			(pts
				(xy -2.0066 10.668) (xy -2.0066 6.9088) (xy -3.8608 6.9088) (xy -3.8608 -1.143) (xy 3.8608 -1.143)
				(xy 3.8608 6.9088) (xy 2.0066 6.9088) (xy 2.0066 10.668)
			)
			(stroke
				(width 0)
				(type default)
			)
			(fill no)
			(layer "F.Fab")
		)
		(pad "1" thru_hole circle
			(at 2.54 0 270)
			(size 1.27 1.27)
			(drill 0.889)
			(layers "*.Cu" "*.Mask")
			(remove_unused_layers no)
			(net "LED_DR_LED0_BLUE")
			(clearance 0.1651)
			(thermal_gap 0.1651)
		)
		(pad "2" thru_hole circle
			(at 0 0 270)
			(size 1.27 1.27)
			(drill 0.889)
			(layers "*.Cu" "*.Mask")
			(remove_unused_layers no)
			(net "LED_DR_LED0_K")
			(clearance 0.1651)
			(thermal_gap 0.1651)
		)
		(pad "3" thru_hole circle
			(at -2.54 0 270)
			(size 1.27 1.27)
			(drill 0.889)
			(layers "*.Cu" "*.Mask")
			(remove_unused_layers no)
			(net "LED_DR_LED0")
			(clearance 0.1651)
			(thermal_gap 0.1651)
		)
	)
	(footprint ""
		(layer "F.Cu")
		(at 36.7284 -478.4598 90)
		(property "Reference" "C49"
			(at 0 0 90)
			(layer "F.SilkS")
			(hide yes)
			(effects
				(font
					(size 1.27 1.27)
				)
			)
		)
		(property "Value" "SCD1U50V3KX-GP"
			(at 0 -2.8194 90)
			(unlocked yes)
			(layer "F.Fab")
			(hide yes)
			(effects
				(font
					(size 1.016 1.016)
					(thickness 0.1524)
				)
			)
		)
		(property "Device Type" "C603H36"
			(at 0 -4.3434 90)
			(unlocked yes)
			(layer "F.Fab")
			(hide yes)
			(effects
				(font
					(size 1.016 1.016)
					(thickness 0.1524)
				)
			)
		)
		(duplicate_pad_numbers_are_jumpers no)
		(fp_line
			(start 0.508 0)
			(end -0.508 0)
			(stroke
				(width 0.2032)
				(type default)
			)
			(layer "F.SilkS")
		)
		(fp_rect
			(start -0.5842 1.3335)
			(end 0.5842 -1.3335)
			(stroke
				(width 0)
				(type default)
			)
			(fill no)
			(layer "F.CrtYd")
		)
		(fp_rect
			(start -0.5842 1.3335)
			(end 0.5842 -1.3335)
			(stroke
				(width 0)
				(type default)
			)
			(fill no)
			(layer "F.Fab")
		)
		(pad "1" smd custom
			(at 0 -0.762 90)
			(size 0.2159 0.2159)
			(layers "F.Cu" "F.Mask" "F.Paste")
			(net "P12V")
			(options
				(clearance outline)
				(anchor circle)
			)
			(primitives
				(gr_poly
					(pts
						(arc
							(start -0.3302 -0.4318)
							(mid -0.402042 -0.402042)
							(end -0.4318 -0.3302)
						)
						(arc
							(start -0.4318 0.3302)
							(mid -0.402042 0.402042)
							(end -0.3302 0.4318)
						)
						(arc
							(start 0.3302 0.4318)
							(mid 0.402042 0.402042)
							(end 0.4318 0.3302)
						)
						(arc
							(start 0.4318 -0.3302)
							(mid 0.402042 -0.402042)
							(end 0.3302 -0.4318)
						)
					)
					(width 0)
					(fill yes)
				)
			)
		)
		(pad "2" smd custom
			(at 0 0.762 90)
			(size 0.2159 0.2159)
			(layers "F.Cu" "F.Mask" "F.Paste")
			(net "GND")
			(options
				(clearance outline)
				(anchor circle)
			)
			(primitives
				(gr_poly
					(pts
						(arc
							(start -0.3302 -0.4318)
							(mid -0.402042 -0.402042)
							(end -0.4318 -0.3302)
						)
						(arc
							(start -0.4318 0.3302)
							(mid -0.402042 0.402042)
							(end -0.3302 0.4318)
						)
						(arc
							(start 0.3302 0.4318)
							(mid 0.402042 0.402042)
							(end 0.4318 0.3302)
						)
						(arc
							(start 0.4318 -0.3302)
							(mid 0.402042 -0.402042)
							(end 0.3302 -0.4318)
						)
					)
					(width 0)
					(fill yes)
				)
			)
		)
	)
	(footprint ""
		(layer "F.Cu")
		(at 39.116 -252.603 -90)
		(property "Reference" "TP19"
			(at 0 0 270)
			(layer "F.SilkS")
			(hide yes)
			(effects
				(font
					(size 1.27 1.27)
				)
			)
		)
		(property "Value" "TPAD32-GP"
			(at 0 -3.166364 270)
			(unlocked yes)
			(layer "F.Fab")
			(hide yes)
			(effects
				(font
					(size 1.016 1.016)
					(thickness 0.1524)
				)
			)
		)
		(property "Device Type" "TPAD32"
			(at 0 -4.690618 270)
			(unlocked yes)
			(layer "F.Fab")
			(hide yes)
			(effects
				(font
					(size 1.016 1.016)
					(thickness 0.1524)
				)
			)
		)
		(duplicate_pad_numbers_are_jumpers no)
		(fp_poly
			(pts
				(arc
					(start 0.7112 0)
					(mid -0.7112 0)
					(end 0.7112 0)
				)
			)
			(stroke
				(width 0)
				(type default)
			)
			(fill no)
			(layer "F.CrtYd")
		)
		(fp_poly
			(pts
				(arc
					(start 0.7112 0)
					(mid -0.7112 0)
					(end 0.7112 0)
				)
			)
			(stroke
				(width 0)
				(type default)
			)
			(fill no)
			(layer "F.Fab")
		)
		(pad "1" smd circle
			(at 0 0 270)
			(size 0.8128 0.8128)
			(layers "F.Cu" "F.Mask" "F.Paste")
			(net "LED_DR_LED6_RESERVE")
		)
	)
	(footprint ""
		(layer "F.Cu")
		(at 21.463 -91.9226 -90)
		(property "Reference" "D15"
			(at 0 0 270)
			(layer "F.SilkS")
			(hide yes)
			(effects
				(font
					(size 1.27 1.27)
				)
			)
		)
		(property "Value" "MBRS340T3G-GP"
			(at 0 -10.6172 270)
			(unlocked yes)
			(layer "F.Fab")
			(hide yes)
			(effects
				(font
					(size 1.016 1.016)
					(thickness 0.1524)
				)
			)
		)
		(property "Device Type" "D8059AKH101"
			(at 0 -12.1412 270)
			(unlocked yes)
			(layer "F.Fab")
			(hide yes)
			(effects
				(font
					(size 1.016 1.016)
					(thickness 0.1524)
				)
			)
		)
		(duplicate_pad_numbers_are_jumpers no)
		(fp_line
			(start 3.175 5.2832)
			(end -3.175 5.2832)
			(stroke
				(width 0.508)
				(type default)
			)
			(layer "F.SilkS")
		)
		(fp_line
			(start -3.175 5.1054)
			(end -3.175 -5.1054)
			(stroke
				(width 0.1524)
				(type default)
			)
			(layer "F.SilkS")
		)
		(fp_line
			(start 3.175 5.1054)
			(end -3.175 5.1054)
			(stroke
				(width 0.1524)
				(type default)
			)
			(layer "F.SilkS")
		)
		(fp_line
			(start -3.175 -5.1054)
			(end 3.175 -5.1054)
			(stroke
				(width 0.1524)
				(type default)
			)
			(layer "F.SilkS")
		)
		(fp_line
			(start 3.175 -5.1054)
			(end 3.175 5.1054)
			(stroke
				(width 0.1524)
				(type default)
			)
			(layer "F.SilkS")
		)
		(fp_rect
			(start -3.429 5.1816)
			(end 3.429 -5.1816)
			(stroke
				(width 0)
				(type default)
			)
			(fill no)
			(layer "F.CrtYd")
		)
		(fp_poly
			(pts
				(xy -3.429 -5.1816) (xy 3.429 -5.1816) (xy 3.429 5.1816) (xy -3.429 5.1816)
			)
			(stroke
				(width 0)
				(type default)
			)
			(fill no)
			(layer "F.Fab")
		)
		(pad "A" smd rect
			(at 0 -3.77571 270)
			(size 3.2512 2.159)
			(layers "F.Cu" "F.Mask" "F.Paste")
			(net "GND")
		)
		(pad "K" smd rect
			(at 0 3.77571 270)
			(size 3.2512 2.159)
			(layers "F.Cu" "F.Mask" "F.Paste")
			(net "P12VU")
		)
	)
)
